(kicad_pcb
	(version 20260206)
	(generator "pcbnew")
	(generator_version "10.0")
	(general
		(thickness 1.6)
		(legacy_teardrops no)
	)
	(paper "A4")
	(title_block
		(title "01162023_DA0F0TEBIF0_F0T_Expander_BD_F_brd_V02_OCP.brd")
		(comment 1 "Grand Teton / footprints 5402-5406 of 9728")
	)
	(layers
		(0 "F.Cu" signal "TOP")
		(4 "In1.Cu" signal "GND")
		(6 "In2.Cu" signal "VCC")
		(8 "In3.Cu" signal "VCC1")
		(10 "In4.Cu" signal "GND1")
		(12 "In5.Cu" signal "IN1")
		(14 "In6.Cu" signal "GND2")
		(16 "In7.Cu" signal "IN2")
		(18 "In8.Cu" signal "GND3")
		(20 "In9.Cu" signal "IN3")
		(22 "In10.Cu" signal "GND4")
		(24 "In11.Cu" signal "IN4")
		(26 "In12.Cu" signal "GND5")
		(28 "In13.Cu" signal "IN5")
		(30 "In14.Cu" signal "GND6")
		(32 "In15.Cu" signal "IN6")
		(34 "In16.Cu" signal "GND7")
		(2 "B.Cu" signal "BOTTOM")
		(9 "F.Adhes" user "F.Adhesive")
		(11 "B.Adhes" user "B.Adhesive")
		(13 "F.Paste" user "Package Geometry/Pastemask Top")
		(15 "B.Paste" user "Package Geometry/Pastemask Bottom")
		(5 "F.SilkS" user "Ref Des/Silkscreen Top")
		(7 "B.SilkS" user "Ref Des/Silkscreen Bottom")
		(1 "F.Mask" user "Board Geometry/Soldermask Top")
		(3 "B.Mask" user "Board Geometry/Soldermask Bottom")
		(17 "Dwgs.User" user "User.Drawings")
		(19 "Cmts.User" user "User.Comments")
		(21 "Eco1.User" user "User.Eco1")
		(23 "Eco2.User" user "User.Eco2")
		(25 "Edge.Cuts" user "Board Geometry/Outline")
		(27 "Margin" user)
		(31 "F.CrtYd" user "Package Geometry/Place Bound Top")
		(29 "B.CrtYd" user "Package Geometry/Place Bound Bottom")
		(35 "F.Fab" user "Ref Des/Assembly Top")
		(33 "B.Fab" user "Ref Des/Assembly Bottom")
	)
	(footprint ""
		(layer "F.Cu")
		(at 219.626434 -368.957606 180)
		(property "Reference" "PU2"
			(at 3.927094 3.71983 0)
			(unlocked yes)
			(layer "F.SilkS")
			(effects
				(font
					(size 0.7874 0.5842)
					(thickness 0.1524)
				)
			)
		)
		(property "Value" ""
			(at 0 0 180)
			(layer "F.Fab")
			(effects
				(font
					(size 1.27 1.27)
				)
			)
		)
		(duplicate_pad_numbers_are_jumpers no)
		(fp_line
			(start 2.567686 2.567686)
			(end 2.567686 -2.567686)
			(stroke
				(width 0.1524)
				(type default)
			)
			(layer "F.SilkS")
		)
		(fp_line
			(start 2.567686 -2.567686)
			(end -2.567686 -2.567686)
			(stroke
				(width 0.1524)
				(type default)
			)
			(layer "F.SilkS")
		)
		(fp_line
			(start -2.567686 2.567686)
			(end 2.567686 2.567686)
			(stroke
				(width 0.1524)
				(type default)
			)
			(layer "F.SilkS")
		)
		(fp_line
			(start -2.567686 -2.567686)
			(end -2.567686 2.567686)
			(stroke
				(width 0.1524)
				(type default)
			)
			(layer "F.SilkS")
		)
		(fp_poly
			(pts
				(xy -3.02768 -3.181096) (xy -3.745992 -2.462784) (xy -2.668524 -2.103374)
			)
			(stroke
				(width 0)
				(type default)
			)
			(fill yes)
			(layer "F.SilkS")
		)
		(fp_line
			(start 2.549906 2.549906)
			(end 2.549906 -2.549906)
			(stroke
				(width 0.1)
				(type default)
			)
			(layer "F.Fab")
		)
		(fp_line
			(start 2.549906 -2.549906)
			(end -2.549906 -2.549906)
			(stroke
				(width 0.1)
				(type default)
			)
			(layer "F.Fab")
		)
		(fp_line
			(start -2.549906 2.549906)
			(end 2.549906 2.549906)
			(stroke
				(width 0.1)
				(type default)
			)
			(layer "F.Fab")
		)
		(fp_line
			(start -2.549906 -2.549906)
			(end -2.549906 2.549906)
			(stroke
				(width 0.1)
				(type default)
			)
			(layer "F.Fab")
		)
		(fp_poly
			(pts
				(xy -3.806698 -2.25806) (xy -3.806698 -1.24206) (xy -2.790698 -1.75006)
			)
			(stroke
				(width 0)
				(type default)
			)
			(fill yes)
			(layer "F.Fab")
		)
		(pad "1" smd rect
			(at -2.250186 -1.75006 270)
			(size 0.254 0.3556)
			(layers "F.Cu" "F.Mask" "F.Paste")
			(net "P12V_AUX")
		)
		(pad "2" smd rect
			(at -2.237486 -1.249934 270)
			(size 0.254 0.381)
			(layers "F.Cu" "F.Mask" "F.Paste")
			(net "P12V_AUX")
		)
		(pad "3" smd rect
			(at -2.237486 -0.750062 270)
			(size 0.254 0.381)
			(layers "F.Cu" "F.Mask" "F.Paste")
			(net "HSC_D_OC_1")
		)
		(pad "4" smd rect
			(at -2.237486 -0.249936 270)
			(size 0.254 0.381)
			(layers "F.Cu" "F.Mask" "F.Paste")
			(net "HSC_ON")
		)
		(pad "5" smd rect
			(at -2.237486 0.249936 270)
			(size 0.254 0.381)
			(layers "F.Cu" "F.Mask" "F.Paste")
			(net "HSC_FAULT_N_1")
		)
		(pad "6" smd rect
			(at -2.237486 0.750062 270)
			(size 0.254 0.381)
			(layers "F.Cu" "F.Mask" "F.Paste")
			(net "HSC_FLT_TYPE_1")
		)
		(pad "7" smd rect
			(at -2.237486 1.249934 270)
			(size 0.254 0.381)
			(layers "F.Cu" "F.Mask" "F.Paste")
			(net "Net_9084")
		)
		(pad "8" smd rect
			(at -2.250186 1.75006 270)
			(size 0.254 0.3556)
			(layers "F.Cu" "F.Mask" "F.Paste")
			(net "HSC_MODE_1")
		)
		(pad "9" smd rect
			(at -1.75006 2.250186 180)
			(size 0.254 0.3556)
			(layers "F.Cu" "F.Mask" "F.Paste")
			(net "P12V_STBY")
		)
		(pad "10" smd rect
			(at -1.249934 2.237486 180)
			(size 0.254 0.381)
			(layers "F.Cu" "F.Mask" "F.Paste")
			(net "P12V_STBY")
		)
		(pad "11" smd rect
			(at -0.750062 2.237486 180)
			(size 0.254 0.381)
			(layers "F.Cu" "F.Mask" "F.Paste")
			(net "P12V_STBY")
		)
		(pad "12" smd rect
			(at -0.249936 2.237486 180)
			(size 0.254 0.381)
			(layers "F.Cu" "F.Mask" "F.Paste")
			(net "P12V_STBY")
		)
		(pad "13" smd rect
			(at 0.249936 2.237486 180)
			(size 0.254 0.381)
			(layers "F.Cu" "F.Mask" "F.Paste")
			(net "P12V_STBY")
		)
		(pad "14" smd rect
			(at 0.750062 2.237486 180)
			(size 0.254 0.381)
			(layers "F.Cu" "F.Mask" "F.Paste")
			(net "P12V_STBY")
		)
		(pad "15" smd rect
			(at 1.249934 2.237486 180)
			(size 0.254 0.381)
			(layers "F.Cu" "F.Mask" "F.Paste")
			(net "P12V_STBY")
		)
		(pad "16" smd rect
			(at 1.75006 2.250186 180)
			(size 0.254 0.3556)
			(layers "F.Cu" "F.Mask" "F.Paste")
			(net "P12V_STBY")
		)
		(pad "17" smd rect
			(at 2.250186 1.75006 270)
			(size 0.254 0.3556)
			(layers "F.Cu" "F.Mask" "F.Paste")
			(net "HSC_SCREF_1")
		)
		(pad "18" smd rect
			(at 2.237486 1.249934 270)
			(size 0.254 0.381)
			(layers "F.Cu" "F.Mask" "F.Paste")
			(net "HSC_VTEMP")
		)
		(pad "19" smd rect
			(at 2.237486 0.750062 270)
			(size 0.254 0.381)
			(layers "F.Cu" "F.Mask" "F.Paste")
			(net "HSC_SS")
		)
		(pad "20" smd rect
			(at 2.237486 0.249936 270)
			(size 0.254 0.381)
			(layers "F.Cu" "F.Mask" "F.Paste")
			(net "AGND_HSC")
		)
		(pad "21" smd rect
			(at 2.237486 -0.249936 270)
			(size 0.254 0.381)
			(layers "F.Cu" "F.Mask" "F.Paste")
			(net "HSC_VDD_1")
		)
		(pad "22" smd rect
			(at 2.237486 -0.750062 270)
			(size 0.254 0.381)
			(layers "F.Cu" "F.Mask" "F.Paste")
			(net "HSC_IMON")
		)
		(pad "23" smd rect
			(at 2.237486 -1.249934 270)
			(size 0.254 0.381)
			(layers "F.Cu" "F.Mask" "F.Paste")
			(net "HSC_CS_1")
		)
		(pad "24" smd rect
			(at 2.250186 -1.75006 270)
			(size 0.254 0.3556)
			(layers "F.Cu" "F.Mask" "F.Paste")
			(net "HSC_OCREF")
		)
		(pad "25" smd rect
			(at 1.75006 -2.250186 180)
			(size 0.254 0.3556)
			(layers "F.Cu" "F.Mask" "F.Paste")
			(net "P12V_AUX")
		)
		(pad "26" smd rect
			(at 1.249934 -2.237486 180)
			(size 0.254 0.381)
			(layers "F.Cu" "F.Mask" "F.Paste")
			(net "P12V_AUX")
		)
		(pad "27" smd rect
			(at 0.750062 -2.237486 180)
			(size 0.254 0.381)
			(layers "F.Cu" "F.Mask" "F.Paste")
			(net "P12V_AUX")
		)
		(pad "28" smd rect
			(at 0.249936 -2.237486 180)
			(size 0.254 0.381)
			(layers "F.Cu" "F.Mask" "F.Paste")
			(net "P12V_AUX")
		)
		(pad "29" smd rect
			(at -0.249936 -2.237486 180)
			(size 0.254 0.381)
			(layers "F.Cu" "F.Mask" "F.Paste")
			(net "P12V_AUX")
		)
		(pad "30" smd rect
			(at -0.750062 -2.237486 180)
			(size 0.254 0.381)
			(layers "F.Cu" "F.Mask" "F.Paste")
			(net "P12V_AUX")
		)
		(pad "31" smd rect
			(at -1.249934 -2.237486 180)
			(size 0.254 0.381)
			(layers "F.Cu" "F.Mask" "F.Paste")
			(net "P12V_AUX")
		)
		(pad "32" smd rect
			(at -1.75006 -2.250186 180)
			(size 0.254 0.3556)
			(layers "F.Cu" "F.Mask" "F.Paste")
			(net "P12V_AUX")
		)
		(pad "33" smd rect
			(at 0 0 180)
			(size 3.4036 3.4036)
			(layers "F.Cu" "F.Mask" "F.Paste")
			(net "P12V_STBY")
		)
	)
	(footprint ""
		(layer "F.Cu")
		(at 226.331272 -254.18542 -90)
		(property "Reference" "C4297"
			(at 0 0 270)
			(layer "F.SilkS")
			(hide yes)
			(effects
				(font
					(size 1.27 1.27)
				)
			)
		)
		(property "Value" ""
			(at 0 0 270)
			(layer "F.Fab")
			(effects
				(font
					(size 1.27 1.27)
				)
			)
		)
		(duplicate_pad_numbers_are_jumpers no)
		(fp_line
			(start -1.2954 0.5842)
			(end -1.2954 -0.5842)
			(stroke
				(width 0.1524)
				(type default)
			)
			(layer "F.SilkS")
		)
		(fp_line
			(start 1.2954 0.5842)
			(end -1.2954 0.5842)
			(stroke
				(width 0.1524)
				(type default)
			)
			(layer "F.SilkS")
		)
		(fp_line
			(start -1.2954 -0.5842)
			(end 1.2954 -0.5842)
			(stroke
				(width 0.1524)
				(type default)
			)
			(layer "F.SilkS")
		)
		(fp_line
			(start 1.2954 -0.5842)
			(end 1.2954 0.5842)
			(stroke
				(width 0.1524)
				(type default)
			)
			(layer "F.SilkS")
		)
		(fp_line
			(start -0.8636 0.4572)
			(end -0.8636 0.4064)
			(stroke
				(width 0.1)
				(type default)
			)
			(layer "F.Fab")
		)
		(fp_line
			(start 0.8636 0.4572)
			(end -0.8636 0.4572)
			(stroke
				(width 0.1)
				(type default)
			)
			(layer "F.Fab")
		)
		(fp_line
			(start -1.1938 0.4064)
			(end -1.1938 -0.4064)
			(stroke
				(width 0.1)
				(type default)
			)
			(layer "F.Fab")
		)
		(fp_line
			(start -0.8636 0.4064)
			(end -1.1938 0.4064)
			(stroke
				(width 0.1)
				(type default)
			)
			(layer "F.Fab")
		)
		(fp_line
			(start 0.8636 0.4064)
			(end 0.8636 0.4572)
			(stroke
				(width 0.1)
				(type default)
			)
			(layer "F.Fab")
		)
		(fp_line
			(start 1.1938 0.4064)
			(end 0.8636 0.4064)
			(stroke
				(width 0.1)
				(type default)
			)
			(layer "F.Fab")
		)
		(fp_line
			(start -1.1938 -0.4064)
			(end -0.8636 -0.4064)
			(stroke
				(width 0.1)
				(type default)
			)
			(layer "F.Fab")
		)
		(fp_line
			(start -0.8636 -0.4064)
			(end -0.8636 -0.4572)
			(stroke
				(width 0.1)
				(type default)
			)
			(layer "F.Fab")
		)
		(fp_line
			(start 0.8636 -0.4064)
			(end 1.1938 -0.4064)
			(stroke
				(width 0.1)
				(type default)
			)
			(layer "F.Fab")
		)
		(fp_line
			(start 1.1938 -0.4064)
			(end 1.1938 0.4064)
			(stroke
				(width 0.1)
				(type default)
			)
			(layer "F.Fab")
		)
		(fp_line
			(start -0.8636 -0.4572)
			(end 0.8636 -0.4572)
			(stroke
				(width 0.1)
				(type default)
			)
			(layer "F.Fab")
		)
		(fp_line
			(start 0.8636 -0.4572)
			(end 0.8636 -0.4064)
			(stroke
				(width 0.1)
				(type default)
			)
			(layer "F.Fab")
		)
		(pad "1" smd rect
			(at -0.7366 0 180)
			(size 0.7112 0.8128)
			(layers "F.Cu" "F.Mask" "F.Paste")
			(net "P1V25_SERDES_VDDPLL_PEX1_C7")
		)
		(pad "2" smd rect
			(at 0.7366 0 180)
			(size 0.7112 0.8128)
			(layers "F.Cu" "F.Mask" "F.Paste")
			(net "GND")
		)
	)
	(footprint ""
		(layer "F.Cu")
		(at 450.19595 -113.547398 90)
		(property "Reference" "PR7049"
			(at 0 0 90)
			(layer "F.SilkS")
			(hide yes)
			(effects
				(font
					(size 1.27 1.27)
				)
			)
		)
		(property "Value" ""
			(at 0 0 90)
			(layer "F.Fab")
			(effects
				(font
					(size 1.27 1.27)
				)
			)
		)
		(duplicate_pad_numbers_are_jumpers no)
		(fp_line
			(start 0.7874 -0.4064)
			(end 0.7874 0.4064)
			(stroke
				(width 0.1524)
				(type default)
			)
			(layer "F.SilkS")
		)
		(fp_line
			(start -0.7874 -0.4064)
			(end 0.7874 -0.4064)
			(stroke
				(width 0.1524)
				(type default)
			)
			(layer "F.SilkS")
		)
		(fp_line
			(start 0.7874 0.4064)
			(end -0.7874 0.4064)
			(stroke
				(width 0.1524)
				(type default)
			)
			(layer "F.SilkS")
		)
		(fp_line
			(start -0.7874 0.4064)
			(end -0.7874 -0.4064)
			(stroke
				(width 0.1524)
				(type default)
			)
			(layer "F.SilkS")
		)
		(fp_line
			(start -0.12065 -0.305054)
			(end -0.12065 -0.2794)
			(stroke
				(width 0.1)
				(type default)
			)
			(layer "F.Fab")
		)
		(fp_line
			(start -0.67945 -0.305054)
			(end -0.12065 -0.305054)
			(stroke
				(width 0.1)
				(type default)
			)
			(layer "F.Fab")
		)
		(fp_line
			(start 0.67945 -0.3048)
			(end 0.67945 0.3048)
			(stroke
				(width 0.1)
				(type default)
			)
			(layer "F.Fab")
		)
		(fp_line
			(start 0.12065 -0.3048)
			(end 0.67945 -0.3048)
			(stroke
				(width 0.1)
				(type default)
			)
			(layer "F.Fab")
		)
		(fp_line
			(start 0.12065 -0.2794)
			(end 0.12065 -0.3048)
			(stroke
				(width 0.1)
				(type default)
			)
			(layer "F.Fab")
		)
		(fp_line
			(start -0.12065 -0.2794)
			(end 0.12065 -0.2794)
			(stroke
				(width 0.1)
				(type default)
			)
			(layer "F.Fab")
		)
		(fp_line
			(start 0.120396 0.2794)
			(end -0.12065 0.2794)
			(stroke
				(width 0.1)
				(type default)
			)
			(layer "F.Fab")
		)
		(fp_line
			(start -0.12065 0.2794)
			(end -0.12065 0.3048)
			(stroke
				(width 0.1)
				(type default)
			)
			(layer "F.Fab")
		)
		(fp_line
			(start 0.67945 0.3048)
			(end 0.120396 0.3048)
			(stroke
				(width 0.1)
				(type default)
			)
			(layer "F.Fab")
		)
		(fp_line
			(start 0.120396 0.3048)
			(end 0.120396 0.2794)
			(stroke
				(width 0.1)
				(type default)
			)
			(layer "F.Fab")
		)
		(fp_line
			(start -0.12065 0.3048)
			(end -0.67945 0.3048)
			(stroke
				(width 0.1)
				(type default)
			)
			(layer "F.Fab")
		)
		(fp_line
			(start -0.67945 0.3048)
			(end -0.67945 -0.305054)
			(stroke
				(width 0.1)
				(type default)
			)
			(layer "F.Fab")
		)
		(pad "1" smd circle
			(at -0.40005 0 90)
			(size 0 0)
			(layers "F.Cu" "F.Mask" "F.Paste")
			(net "P12V_NIC7_R")
		)
		(pad "2" smd circle
			(at 0.40005 0 90)
			(size 0 0)
			(layers "F.Cu" "F.Mask" "F.Paste")
			(net "P12V_NIC7_CO_AVIN_PD")
		)
	)
	(footprint ""
		(layer "F.Cu")
		(at 258.170426 -243.540788 180)
		(property "Reference" "R6578"
			(at 0 0 180)
			(layer "F.SilkS")
			(hide yes)
			(effects
				(font
					(size 1.27 1.27)
				)
			)
		)
		(property "Value" ""
			(at 0 0 180)
			(layer "F.Fab")
			(effects
				(font
					(size 1.27 1.27)
				)
			)
		)
		(duplicate_pad_numbers_are_jumpers no)
		(fp_line
			(start 0.7874 0.4064)
			(end -0.7874 0.4064)
			(stroke
				(width 0.1524)
				(type default)
			)
			(layer "F.SilkS")
		)
		(fp_line
			(start 0.7874 -0.4064)
			(end 0.7874 0.4064)
			(stroke
				(width 0.1524)
				(type default)
			)
			(layer "F.SilkS")
		)
		(fp_line
			(start -0.7874 0.4064)
			(end -0.7874 -0.4064)
			(stroke
				(width 0.1524)
				(type default)
			)
			(layer "F.SilkS")
		)
		(fp_line
			(start -0.7874 -0.4064)
			(end 0.7874 -0.4064)
			(stroke
				(width 0.1524)
				(type default)
			)
			(layer "F.SilkS")
		)
		(fp_line
			(start 0.67945 0.3048)
			(end 0.120396 0.3048)
			(stroke
				(width 0.1)
				(type default)
			)
			(layer "F.Fab")
		)
		(fp_line
			(start 0.67945 -0.3048)
			(end 0.67945 0.3048)
			(stroke
				(width 0.1)
				(type default)
			)
			(layer "F.Fab")
		)
		(fp_line
			(start 0.12065 -0.2794)
			(end 0.12065 -0.3048)
			(stroke
				(width 0.1)
				(type default)
			)
			(layer "F.Fab")
		)
		(fp_line
			(start 0.12065 -0.3048)
			(end 0.67945 -0.3048)
			(stroke
				(width 0.1)
				(type default)
			)
			(layer "F.Fab")
		)
		(fp_line
			(start 0.120396 0.3048)
			(end 0.120396 0.2794)
			(stroke
				(width 0.1)
				(type default)
			)
			(layer "F.Fab")
		)
		(fp_line
			(start 0.120396 0.2794)
			(end -0.12065 0.2794)
			(stroke
				(width 0.1)
				(type default)
			)
			(layer "F.Fab")
		)
		(fp_line
			(start -0.12065 0.3048)
			(end -0.67945 0.3048)
			(stroke
				(width 0.1)
				(type default)
			)
			(layer "F.Fab")
		)
		(fp_line
			(start -0.12065 0.2794)
			(end -0.12065 0.3048)
			(stroke
				(width 0.1)
				(type default)
			)
			(layer "F.Fab")
		)
		(fp_line
			(start -0.12065 -0.2794)
			(end 0.12065 -0.2794)
			(stroke
				(width 0.1)
				(type default)
			)
			(layer "F.Fab")
		)
		(fp_line
			(start -0.12065 -0.305054)
			(end -0.12065 -0.2794)
			(stroke
				(width 0.1)
				(type default)
			)
			(layer "F.Fab")
		)
		(fp_line
			(start -0.67945 0.3048)
			(end -0.67945 -0.305054)
			(stroke
				(width 0.1)
				(type default)
			)
			(layer "F.Fab")
		)
		(fp_line
			(start -0.67945 -0.305054)
			(end -0.12065 -0.305054)
			(stroke
				(width 0.1)
				(type default)
			)
			(layer "F.Fab")
		)
		(pad "1" smd circle
			(at -0.40005 0 180)
			(size 0 0)
			(layers "F.Cu" "F.Mask" "F.Paste")
			(net "PWR_EN_PEX_R")
		)
		(pad "2" smd circle
			(at 0.40005 0 180)
			(size 0 0)
			(layers "F.Cu" "F.Mask" "F.Paste")
			(net "PEX2_P1V8_PLL_EN")
		)
	)
	(footprint ""
		(layer "F.Cu")
		(at 357.619808 -162.003994 90)
		(property "Reference" "PR7057"
			(at 0 0 90)
			(layer "F.SilkS")
			(hide yes)
			(effects
				(font
					(size 1.27 1.27)
				)
			)
		)
		(property "Value" ""
			(at 0 0 90)
			(layer "F.Fab")
			(effects
				(font
					(size 1.27 1.27)
				)
			)
		)
		(duplicate_pad_numbers_are_jumpers no)
		(fp_line
			(start 0.7874 -0.4064)
			(end 0.7874 0.4064)
			(stroke
				(width 0.1524)
				(type default)
			)
			(layer "F.SilkS")
		)
		(fp_line
			(start -0.7874 -0.4064)
			(end 0.7874 -0.4064)
			(stroke
				(width 0.1524)
				(type default)
			)
			(layer "F.SilkS")
		)
		(fp_line
			(start 0.7874 0.4064)
			(end -0.7874 0.4064)
			(stroke
				(width 0.1524)
				(type default)
			)
			(layer "F.SilkS")
		)
		(fp_line
			(start -0.7874 0.4064)
			(end -0.7874 -0.4064)
			(stroke
				(width 0.1524)
				(type default)
			)
			(layer "F.SilkS")
		)
		(fp_line
			(start -0.12065 -0.305054)
			(end -0.12065 -0.2794)
			(stroke
				(width 0.1)
				(type default)
			)
			(layer "F.Fab")
		)
		(fp_line
			(start -0.67945 -0.305054)
			(end -0.12065 -0.305054)
			(stroke
				(width 0.1)
				(type default)
			)
			(layer "F.Fab")
		)
		(fp_line
			(start 0.67945 -0.3048)
			(end 0.67945 0.3048)
			(stroke
				(width 0.1)
				(type default)
			)
			(layer "F.Fab")
		)
		(fp_line
			(start 0.12065 -0.3048)
			(end 0.67945 -0.3048)
			(stroke
				(width 0.1)
				(type default)
			)
			(layer "F.Fab")
		)
		(fp_line
			(start 0.12065 -0.2794)
			(end 0.12065 -0.3048)
			(stroke
				(width 0.1)
				(type default)
			)
			(layer "F.Fab")
		)
		(fp_line
			(start -0.12065 -0.2794)
			(end 0.12065 -0.2794)
			(stroke
				(width 0.1)
				(type default)
			)
			(layer "F.Fab")
		)
		(fp_line
			(start 0.120396 0.2794)
			(end -0.12065 0.2794)
			(stroke
				(width 0.1)
				(type default)
			)
			(layer "F.Fab")
		)
		(fp_line
			(start -0.12065 0.2794)
			(end -0.12065 0.3048)
			(stroke
				(width 0.1)
				(type default)
			)
			(layer "F.Fab")
		)
		(fp_line
			(start 0.67945 0.3048)
			(end 0.120396 0.3048)
			(stroke
				(width 0.1)
				(type default)
			)
			(layer "F.Fab")
		)
		(fp_line
			(start 0.120396 0.3048)
			(end 0.120396 0.2794)
			(stroke
				(width 0.1)
				(type default)
			)
			(layer "F.Fab")
		)
		(fp_line
			(start -0.12065 0.3048)
			(end -0.67945 0.3048)
			(stroke
				(width 0.1)
				(type default)
			)
			(layer "F.Fab")
		)
		(fp_line
			(start -0.67945 0.3048)
			(end -0.67945 -0.305054)
			(stroke
				(width 0.1)
				(type default)
			)
			(layer "F.Fab")
		)
		(pad "1" smd circle
			(at -0.40005 0 90)
			(size 0 0)
			(layers "F.Cu" "F.Mask" "F.Paste")
			(net "P12V_NIC6_CO_IMON_VR")
		)
		(pad "2" smd circle
			(at 0.40005 0 90)
			(size 0 0)
			(layers "F.Cu" "F.Mask" "F.Paste")
			(net "GND")
		)
	)
)
